FILE_TYPE=LIBRARY_PARTS;
TIME=' Created/Modified on Thu Mar 18 15:59:00 2010' ;
primitive 'PCA9517ADP';
  pin
    'ENABLE':
      PIN_NUMBER='(5)';
      INPUT_LOAD='(-0.01,0.01)';
      OUTPUT_LOAD='(1.0,-1.0)';
      BIDIRECTIONAL='TRUE';
    'VCCB':
      PIN_NUMBER='(8)';
      INPUT_LOAD='(-0.01,0.01)';
      OUTPUT_LOAD='(1.0,-1.0)';
      BIDIRECTIONAL='TRUE';
    'SCLA':
      PIN_NUMBER='(2)';
      INPUT_LOAD='(-0.01,0.01)';
      OUTPUT_LOAD='(1.0,-1.0)';
      BIDIRECTIONAL='TRUE';
    'SDAA':
      PIN_NUMBER='(3)';
      INPUT_LOAD='(-0.01,0.01)';
      OUTPUT_LOAD='(1.0,-1.0)';
      BIDIRECTIONAL='TRUE';
    'SDAB':
      PIN_NUMBER='(6)';
      INPUT_LOAD='(-0.01,0.01)';
      OUTPUT_LOAD='(1.0,-1.0)';
      BIDIRECTIONAL='TRUE';
    'SCLB':
      PIN_NUMBER='(7)';
      INPUT_LOAD='(-0.01,0.01)';
      OUTPUT_LOAD='(1.0,-1.0)';
      BIDIRECTIONAL='TRUE';
    'VCCA':
      PIN_NUMBER='(1)';
      PINUSE='POWER';
    'GND':
      PIN_NUMBER='(4)';
      PINUSE='POWER';
  end_pin;
  body
    CLASS='DISCRETE';
    PART_NAME='PCA9517ADP';
    PHYS_DES_PREFIX='D';
  end_body;
end_primitive;
END.
